(kicad_pcb
	(version 20241229)
	(generator "pcbnew")
	(generator_version "9.0")
	(general
		(thickness 1.63)
		(legacy_teardrops no)
	)
	(paper "A4")
	(title_block
		(title "CM4 Baseboard")
		(date "2026-01-05")
		(rev "1.1.1")
		(company "Antmicro Ltd")
		(comment 1 "www.antmicro.com")
		(comment 9 "footprints 376-376 of 506")
	)
	(layers
		(0 "F.Cu" signal)
		(4 "In1.Cu" power)
		(6 "In2.Cu" power)
		(8 "In3.Cu" signal)
		(10 "In4.Cu" signal)
		(2 "B.Cu" signal)
		(9 "F.Adhes" user "F.Adhesive")
		(11 "B.Adhes" user "B.Adhesive")
		(13 "F.Paste" user)
		(15 "B.Paste" user)
		(5 "F.SilkS" user "F.Silkscreen")
		(7 "B.SilkS" user "B.Silkscreen")
		(1 "F.Mask" user)
		(3 "B.Mask" user)
		(17 "Dwgs.User" user "User.Drawings")
		(19 "Cmts.User" user "User.Comments")
		(21 "Eco1.User" user "User.Eco1")
		(23 "Eco2.User" user "User.Eco2")
		(25 "Edge.Cuts" user)
		(27 "Margin" user)
		(31 "F.CrtYd" user "F.Courtyard")
		(29 "B.CrtYd" user "B.Courtyard")
		(35 "F.Fab" user)
		(33 "B.Fab" user)
	)
	(footprint "antmicro-footprints:Bus_M.2_Socket_Key_M_TE_1-2199230-6"
		(locked yes)
		(layer "B.Cu")
		(at 124.392962 124.767 90)
		(property "Reference" "J501"
			(at 5.0905 5.705 90)
			(layer "B.SilkS")
			(effects
				(font
					(size 0.7 0.7)
					(thickness 0.15)
				)
				(justify right bottom mirror)
			)
		)
		(property "Value" "Bus_M.2_1-2199230-6"
			(at -11.25 -6.124 90)
			(layer "B.Fab")
			(effects
				(font
					(size 0.7 0.7)
					(thickness 0.15)
				)
				(justify right bottom mirror)
			)
		)
		(property "Datasheet" "https://www.te.com/commerce/DocumentDelivery/DDEController?Action=srchrtrv&DocNm=2199230&DocType=Customer+Drawing&DocLang=English"
			(at 0 0 90)
			(layer "B.Fab")
			(hide yes)
			(effects
				(font
					(size 1.27 1.27)
					(thickness 0.15)
				)
			)
		)
		(property "Manufacturer" "TE Connectivity"
			(at 0 0 90)
			(unlocked yes)
			(layer "B.Fab")
			(hide yes)
			(effects
				(font
					(size 1 1)
					(thickness 0.15)
				)
				(justify mirror)
			)
		)
		(property "MPN" "1-2199230-6"
			(at 0 0 90)
			(unlocked yes)
			(layer "B.Fab")
			(hide yes)
			(effects
				(font
					(size 1 1)
					(thickness 0.15)
				)
				(justify mirror)
			)
		)
		(property "Author" "Antmicro"
			(at 0 0 90)
			(unlocked yes)
			(layer "B.Fab")
			(hide yes)
			(effects
				(font
					(size 1 1)
					(thickness 0.15)
				)
				(justify mirror)
			)
		)
		(property "License" "Apache-2.0"
			(at 0 0 90)
			(unlocked yes)
			(layer "B.Fab")
			(hide yes)
			(effects
				(font
					(size 1 1)
					(thickness 0.15)
				)
				(justify mirror)
			)
		)
		(sheetname "/NVMe & microSD/")
		(sheetfile "nvme-micro-sd.kicad_sch")
		(attr smd)
		(fp_line
			(start 10.948 -3.999)
			(end 10.948 -2.3)
			(stroke
				(width 0.15)
				(type solid)
			)
			(layer "B.SilkS")
		)
		(fp_line
			(start 9.448 -3.999)
			(end 10.948 -3.999)
			(stroke
				(width 0.15)
				(type solid)
			)
			(layer "B.SilkS")
		)
		(fp_line
			(start 5.347 -3.999)
			(end 7.148 -3.999)
			(stroke
				(width 0.15)
				(type solid)
			)
			(layer "B.SilkS")
		)
		(fp_line
			(start -10.951 -3.999)
			(end -9.352 -3.999)
			(stroke
				(width 0.15)
				(type solid)
			)
			(layer "B.SilkS")
		)
		(fp_line
			(start -10.951 -2.7)
			(end -10.951 -3.999)
			(stroke
				(width 0.15)
				(type solid)
			)
			(layer "B.SilkS")
		)
		(fp_line
			(start 10.948 -0.449)
			(end 10.948 1.301)
			(stroke
				(width 0.15)
				(type solid)
			)
			(layer "B.SilkS")
		)
		(fp_line
			(start -10.951 1.401)
			(end -10.951 -0.55)
			(stroke
				(width 0.15)
				(type solid)
			)
			(layer "B.SilkS")
		)
		(fp_line
			(start 5.097 3.75)
			(end 6.898 3.75)
			(stroke
				(width 0.15)
				(type solid)
			)
			(layer "B.SilkS")
		)
		(fp_circle
			(center -9.25 4.875)
			(end -9.201 4.826)
			(stroke
				(width 0.15)
				(type solid)
			)
			(fill yes)
			(layer "B.SilkS")
		)
		(fp_circle
			(center -9.25 5.651)
			(end -9.2 5.651)
			(stroke
				(width 0.15)
				(type solid)
			)
			(fill yes)
			(layer "B.SilkS")
		)
		(fp_line
			(start 11.15 -4.78)
			(end 11.15 4.83)
			(stroke
				(width 0.05)
				(type solid)
			)
			(layer "B.CrtYd")
		)
		(fp_line
			(start -11.16 -4.78)
			(end 11.15 -4.78)
			(stroke
				(width 0.05)
				(type solid)
			)
			(layer "B.CrtYd")
		)
		(fp_line
			(start 11.15 4.83)
			(end -11.16 4.83)
			(stroke
				(width 0.05)
				(type solid)
			)
			(layer "B.CrtYd")
		)
		(fp_line
			(start -11.16 4.83)
			(end -11.16 -4.78)
			(stroke
				(width 0.05)
				(type solid)
			)
			(layer "B.CrtYd")
		)
		(fp_line
			(start 10.95 -4.2)
			(end -10.949 -4.2)
			(stroke
				(width 0.15)
				(type solid)
			)
			(layer "B.Fab")
		)
		(fp_line
			(start -10.949 -4.2)
			(end -10.949 3.55)
			(stroke
				(width 0.15)
				(type solid)
			)
			(layer "B.Fab")
		)
		(fp_line
			(start -10.949 3.55)
			(end -10.4 4.1)
			(stroke
				(width 0.15)
				(type solid)
			)
			(layer "B.Fab")
		)
		(fp_line
			(start 10.95 4.1)
			(end 10.95 -4.2)
			(stroke
				(width 0.15)
				(type solid)
			)
			(layer "B.Fab")
		)
		(fp_line
			(start -10.4 4.1)
			(end 10.95 4.1)
			(stroke
				(width 0.15)
				(type solid)
			)
			(layer "B.Fab")
		)
		(fp_text user "License: Apache-2.0"
			(at -11.35 -10.525 270)
			(layer "B.Fab")
			(effects
				(font
					(size 0.7 0.7)
					(thickness 0.15)
				)
				(justify left bottom mirror)
			)
		)
		(fp_text user "Author: Antmicro"
			(at -11.35 -9.325 270)
			(layer "B.Fab")
			(effects
				(font
					(size 0.7 0.7)
					(thickness 0.15)
				)
				(justify left bottom mirror)
			)
		)
		(fp_text user "${REFERENCE}"
			(at -11.35 -8.124 270)
			(layer "B.Fab")
			(effects
				(font
					(size 0.7 0.7)
					(thickness 0.15)
				)
				(justify left bottom mirror)
			)
		)
		(pad "" np_thru_hole circle
			(at -10 -1.499 90)
			(size 1.1 1.1)
			(drill 1.1)
			(layers "*.Mask")
		)
		(pad "" np_thru_hole circle
			(at 9.997 -1.499 90)
			(size 1.6 1.6)
			(drill 1.6)
			(layers "*.Mask")
		)
		(pad "1" smd rect
			(at -9.25 3.775 90)
			(size 0.3 1.55)
			(layers "B.Cu" "B.Mask" "B.Paste")
			(net 3 "GND")
			(pinfunction "GND")
			(pintype "power_in")
		)
		(pad "2" smd rect
			(at -9.003 -3.773 90)
			(size 0.3 1.55)
			(layers "B.Cu" "B.Mask" "B.Paste")
			(net 65 "3V3_SSD")
			(pinfunction "3V3")
			(pintype "passive")
		)
		(pad "3" smd rect
			(at -8.753 3.775 90)
			(size 0.3 1.55)
			(layers "B.Cu" "B.Mask" "B.Paste")
			(net 3 "GND")
			(pinfunction "GND")
			(pintype "passive")
		)
		(pad "4" smd rect
			(at -8.503 -3.773 90)
			(size 0.3 1.55)
			(layers "B.Cu" "B.Mask" "B.Paste")
			(net 65 "3V3_SSD")
			(pinfunction "3V3")
			(pintype "passive")
		)
		(pad "5" smd rect
			(at -8.253 3.775 90)
			(size 0.3 1.55)
			(layers "B.Cu" "B.Mask" "B.Paste")
			(net 158 "/Compute module/NVMe.RX3_N")
			(pinfunction "PER3_N")
			(pintype "output")
		)
		(pad "6" smd rect
			(at -8.001 -3.773 90)
			(size 0.3 1.55)
			(layers "B.Cu" "B.Mask" "B.Paste")
			(net 246 "unconnected-(J501-NC-Pad6)")
			(pinfunction "NC")
			(pintype "no_connect")
		)
		(pad "7" smd rect
			(at -7.752 3.775 90)
			(size 0.3 1.55)
			(layers "B.Cu" "B.Mask" "B.Paste")
			(net 159 "/Compute module/NVMe.RX3_P")
			(pinfunction "PER3_P")
			(pintype "output")
		)
		(pad "8" smd rect
			(at -7.502 -3.773 90)
			(size 0.3 1.55)
			(layers "B.Cu" "B.Mask" "B.Paste")
			(net 245 "unconnected-(J501-NC-Pad8)")
			(pinfunction "NC")
			(pintype "no_connect")
		)
		(pad "9" smd rect
			(at -7.252 3.775 90)
			(size 0.3 1.55)
			(layers "B.Cu" "B.Mask" "B.Paste")
			(net 3 "GND")
			(pinfunction "GND")
			(pintype "passive")
		)
		(pad "10" smd rect
			(at -7.002 -3.773 90)
			(size 0.3 1.55)
			(layers "B.Cu" "B.Mask" "B.Paste")
			(net 470 "Net-(D503-C)")
			(pinfunction "LED")
			(pintype "passive")
		)
		(pad "11" smd rect
			(at -6.752 3.775 90)
			(size 0.3 1.55)
			(layers "B.Cu" "B.Mask" "B.Paste")
			(net 160 "/Compute module/NVMe.TX3_N")
			(pinfunction "PET3_N")
			(pintype "input")
		)
		(pad "12" smd rect
			(at -6.502 -3.773 90)
			(size 0.3 1.55)
			(layers "B.Cu" "B.Mask" "B.Paste")
			(net 65 "3V3_SSD")
			(pinfunction "3V3")
			(pintype "passive")
		)
		(pad "13" smd rect
			(at -6.252 3.775 90)
			(size 0.3 1.55)
			(layers "B.Cu" "B.Mask" "B.Paste")
			(net 161 "/Compute module/NVMe.TX3_P")
			(pinfunction "PET3_P")
			(pintype "input")
		)
		(pad "14" smd rect
			(at -6.002 -3.773 90)
			(size 0.3 1.55)
			(layers "B.Cu" "B.Mask" "B.Paste")
			(net 65 "3V3_SSD")
			(pinfunction "3V3")
			(pintype "passive")
		)
		(pad "15" smd rect
			(at -5.752 3.775 90)
			(size 0.3 1.55)
			(layers "B.Cu" "B.Mask" "B.Paste")
			(net 3 "GND")
			(pinfunction "GND")
			(pintype "passive")
		)
		(pad "16" smd rect
			(at -5.502 -3.773 90)
			(size 0.3 1.55)
			(layers "B.Cu" "B.Mask" "B.Paste")
			(net 65 "3V3_SSD")
			(pinfunction "3V3")
			(pintype "passive")
		)
		(pad "17" smd rect
			(at -5.252 3.775 90)
			(size 0.3 1.55)
			(layers "B.Cu" "B.Mask" "B.Paste")
			(net 162 "/Compute module/NVMe.RX2_N")
			(pinfunction "PER2_N")
			(pintype "output")
		)
		(pad "18" smd rect
			(at -5.002 -3.773 90)
			(size 0.3 1.55)
			(layers "B.Cu" "B.Mask" "B.Paste")
			(net 65 "3V3_SSD")
			(pinfunction "3V3")
			(pintype "passive")
		)
		(pad "19" smd rect
			(at -4.752 3.775 90)
			(size 0.3 1.55)
			(layers "B.Cu" "B.Mask" "B.Paste")
			(net 163 "/Compute module/NVMe.RX2_P")
			(pinfunction "PER2_P")
			(pintype "output")
		)
		(pad "20" smd rect
			(at -4.502 -3.773 90)
			(size 0.3 1.55)
			(layers "B.Cu" "B.Mask" "B.Paste")
			(net 244 "unconnected-(J501-NC-Pad20)")
			(pinfunction "NC")
			(pintype "no_connect")
		)
		(pad "21" smd rect
			(at -4.252 3.775 90)
			(size 0.3 1.55)
			(layers "B.Cu" "B.Mask" "B.Paste")
			(net 3 "GND")
			(pinfunction "GND")
			(pintype "passive")
		)
		(pad "22" smd rect
			(at -4.002 -3.773 90)
			(size 0.3 1.55)
			(layers "B.Cu" "B.Mask" "B.Paste")
			(net 202 "unconnected-(J501-NC-Pad22)")
			(pinfunction "NC")
			(pintype "no_connect")
		)
		(pad "23" smd rect
			(at -3.751 3.775 90)
			(size 0.3 1.55)
			(layers "B.Cu" "B.Mask" "B.Paste")
			(net 164 "/Compute module/NVMe.TX2_N")
			(pinfunction "PET2_N")
			(pintype "input")
		)
		(pad "24" smd rect
			(at -3.501 -3.773 90)
			(size 0.3 1.55)
			(layers "B.Cu" "B.Mask" "B.Paste")
			(net 201 "unconnected-(J501-NC-Pad24)")
			(pinfunction "NC")
			(pintype "no_connect")
		)
		(pad "25" smd rect
			(at -3.251 3.775 90)
			(size 0.3 1.55)
			(layers "B.Cu" "B.Mask" "B.Paste")
			(net 165 "/Compute module/NVMe.TX2_P")
			(pinfunction "PET2_P")
			(pintype "input")
		)
		(pad "26" smd rect
			(at -3.001 -3.773 90)
			(size 0.3 1.55)
			(layers "B.Cu" "B.Mask" "B.Paste")
			(net 200 "unconnected-(J501-NC-Pad26)")
			(pinfunction "NC")
			(pintype "no_connect")
		)
		(pad "27" smd rect
			(at -2.751 3.775 90)
			(size 0.3 1.55)
			(layers "B.Cu" "B.Mask" "B.Paste")
			(net 3 "GND")
			(pinfunction "GND")
			(pintype "passive")
		)
		(pad "28" smd rect
			(at -2.501 -3.773 90)
			(size 0.3 1.55)
			(layers "B.Cu" "B.Mask" "B.Paste")
			(net 199 "unconnected-(J501-NC-Pad28)")
			(pinfunction "NC")
			(pintype "no_connect")
		)
		(pad "29" smd rect
			(at -2.251 3.775 90)
			(size 0.3 1.55)
			(layers "B.Cu" "B.Mask" "B.Paste")
			(net 166 "/Compute module/NVMe.RX1_N")
			(pinfunction "PER1_N")
			(pintype "output")
		)
		(pad "30" smd rect
			(at -2.001 -3.773 90)
			(size 0.3 1.55)
			(layers "B.Cu" "B.Mask" "B.Paste")
			(net 198 "unconnected-(J501-NC-Pad30)")
			(pinfunction "NC")
			(pintype "no_connect")
		)
		(pad "31" smd rect
			(at -1.752 3.775 90)
			(size 0.3 1.55)
			(layers "B.Cu" "B.Mask" "B.Paste")
			(net 167 "/Compute module/NVMe.RX1_P")
			(pinfunction "PER1_P")
			(pintype "output")
		)
		(pad "32" smd rect
			(at -1.502 -3.773 90)
			(size 0.3 1.55)
			(layers "B.Cu" "B.Mask" "B.Paste")
			(net 197 "unconnected-(J501-NC-Pad32)")
			(pinfunction "NC")
			(pintype "no_connect")
		)
		(pad "33" smd rect
			(at -1.252 3.775 90)
			(size 0.3 1.55)
			(layers "B.Cu" "B.Mask" "B.Paste")
			(net 3 "GND")
			(pinfunction "GND")
			(pintype "passive")
		)
		(pad "34" smd rect
			(at -1.002 -3.773 90)
			(size 0.3 1.55)
			(layers "B.Cu" "B.Mask" "B.Paste")
			(net 196 "unconnected-(J501-NC-Pad34)")
			(pinfunction "NC")
			(pintype "no_connect")
		)
		(pad "35" smd rect
			(at -0.751 3.775 90)
			(size 0.3 1.55)
			(layers "B.Cu" "B.Mask" "B.Paste")
			(net 168 "/Compute module/NVMe.TX1_N")
			(pinfunction "PET1_N")
			(pintype "input")
		)
		(pad "36" smd rect
			(at -0.501 -3.773 90)
			(size 0.3 1.55)
			(layers "B.Cu" "B.Mask" "B.Paste")
			(net 195 "unconnected-(J501-NC-Pad36)")
			(pinfunction "NC")
			(pintype "no_connect")
		)
		(pad "37" smd rect
			(at -0.251 3.775 90)
			(size 0.3 1.55)
			(layers "B.Cu" "B.Mask" "B.Paste")
			(net 169 "/Compute module/NVMe.TX1_P")
			(pinfunction "PET1_P")
			(pintype "input")
		)
		(pad "38" smd rect
			(at -0.001 -3.773 90)
			(size 0.3 1.55)
			(layers "B.Cu" "B.Mask" "B.Paste")
			(net 194 "unconnected-(J501-NC-Pad38)")
			(pinfunction "NC")
			(pintype "no_connect")
		)
		(pad "39" smd rect
			(at 0.248 3.775 90)
			(size 0.3 1.55)
			(layers "B.Cu" "B.Mask" "B.Paste")
			(net 3 "GND")
			(pinfunction "GND")
			(pintype "passive")
		)
		(pad "40" smd rect
			(at 0.498 -3.773 90)
			(size 0.3 1.55)
			(layers "B.Cu" "B.Mask" "B.Paste")
			(net 193 "Net-(J501-SMB_CLK)")
			(pinfunction "SMB_CLK")
			(pintype "input")
		)
		(pad "41" smd rect
			(at 0.748 3.775 90)
			(size 0.3 1.55)
			(layers "B.Cu" "B.Mask" "B.Paste")
			(net 170 "/Compute module/NVMe.RX0_N")
			(pinfunction "PER0_N")
			(pintype "output")
		)
		(pad "42" smd rect
			(at 0.998 -3.773 90)
			(size 0.3 1.55)
			(layers "B.Cu" "B.Mask" "B.Paste")
			(net 192 "Net-(J501-SMB_DATA)")
			(pinfunction "SMB_DATA")
			(pintype "bidirectional")
		)
		(pad "43" smd rect
			(at 1.249 3.775 90)
			(size 0.3 1.55)
			(layers "B.Cu" "B.Mask" "B.Paste")
			(net 171 "/Compute module/NVMe.RX0_P")
			(pinfunction "PER0_P")
			(pintype "output")
		)
		(pad "44" smd rect
			(at 1.499 -3.773 90)
			(size 0.3 1.55)
			(layers "B.Cu" "B.Mask" "B.Paste")
			(net 185 "Net-(J501-ALERT)")
			(pinfunction "ALERT")
			(pintype "output")
		)
		(pad "45" smd rect
			(at 1.749 3.775 90)
			(size 0.3 1.55)
			(layers "B.Cu" "B.Mask" "B.Paste")
			(net 3 "GND")
			(pinfunction "GND")
			(pintype "passive")
		)
		(pad "46" smd rect
			(at 1.999 -3.773 90)
			(size 0.3 1.55)
			(layers "B.Cu" "B.Mask" "B.Paste")
			(net 184 "unconnected-(J501-NC-Pad46)")
			(pinfunction "NC")
			(pintype "no_connect")
		)
		(pad "47" smd rect
			(at 2.249 3.775 90)
			(size 0.3 1.55)
			(layers "B.Cu" "B.Mask" "B.Paste")
			(net 172 "/Compute module/NVMe.TX0_N")
			(pinfunction "PET0_N")
			(pintype "input")
		)
		(pad "48" smd rect
			(at 2.499 -3.773 90)
			(size 0.3 1.55)
			(layers "B.Cu" "B.Mask" "B.Paste")
			(net 183 "unconnected-(J501-NC-Pad48)")
			(pinfunction "NC")
			(pintype "no_connect")
		)
		(pad "49" smd rect
			(at 2.749 3.775 90)
			(size 0.3 1.55)
			(layers "B.Cu" "B.Mask" "B.Paste")
			(net 173 "/Compute module/NVMe.TX0_P")
			(pinfunction "PET0_P")
			(pintype "input")
		)
		(pad "50" smd rect
			(at 2.999 -3.773 90)
			(size 0.3 1.55)
			(layers "B.Cu" "B.Mask" "B.Paste")
			(net 145 "/Compute module/NVMe.~{RST}")
			(pinfunction "~{PERST}")
			(pintype "input")
		)
		(pad "51" smd rect
			(at 3.249 3.775 90)
			(size 0.3 1.55)
			(layers "B.Cu" "B.Mask" "B.Paste")
			(net 3 "GND")
			(pinfunction "GND")
			(pintype "passive")
		)
		(pad "52" smd rect
			(at 3.499 -3.773 90)
			(size 0.3 1.55)
			(layers "B.Cu" "B.Mask" "B.Paste")
			(net 144 "/Compute module/NVMe.~{CLK_REQ}")
			(pinfunction "~{CLKREQ}")
			(pintype "output")
		)
		(pad "53" smd rect
			(at 3.749 3.775 90)
			(size 0.3 1.55)
			(layers "B.Cu" "B.Mask" "B.Paste")
			(net 41 "/Compute module/NVMe.CLK_N")
			(pinfunction "REFCLK_N")
			(pintype "input")
		)
		(pad "54" smd rect
			(at 3.999 -3.773 90)
			(size 0.3 1.55)
			(layers "B.Cu" "B.Mask" "B.Paste")
			(net 182 "Net-(J501-~{PEWAKE})")
			(pinfunction "~{PEWAKE}")
			(pintype "input")
		)
		(pad "55" smd rect
			(at 4.248 3.775 90)
			(size 0.3 1.55)
			(layers "B.Cu" "B.Mask" "B.Paste")
			(net 40 "/Compute module/NVMe.CLK_P")
			(pinfunction "REFCLK_P")
			(pintype "input")
		)
		(pad "56" smd rect
			(at 4.498 -3.773 90)
			(size 0.3 1.55)
			(layers "B.Cu" "B.Mask" "B.Paste")
			(net 181 "unconnected-(J501-NC-Pad56)")
			(pinfunction "NC")
			(pintype "no_connect")
		)
		(pad "57" smd rect
			(at 4.748 3.775 90)
			(size 0.3 1.55)
			(layers "B.Cu" "B.Mask" "B.Paste")
			(net 3 "GND")
			(pinfunction "GND")
			(pintype "passive")
		)
		(pad "58" smd rect
			(at 4.998 -3.773 90)
			(size 0.3 1.55)
			(layers "B.Cu" "B.Mask" "B.Paste")
			(net 180 "unconnected-(J501-NC-Pad58)")
			(pinfunction "NC")
			(pintype "no_connect")
		)
		(pad "67" smd rect
			(at 7.248 3.775 90)
			(size 0.3 1.55)
			(layers "B.Cu" "B.Mask" "B.Paste")
			(net 179 "unconnected-(J501-NC-Pad67)")
			(pinfunction "NC")
			(pintype "no_connect")
		)
		(pad "68" smd rect
			(at 7.498 -3.773 90)
			(size 0.3 1.55)
			(layers "B.Cu" "B.Mask" "B.Paste")
			(net 178 "Net-(J501-SUSCLK)")
			(pinfunction "SUSCLK")
			(pintype "input")
		)
		(pad "69" smd rect
			(at 7.748 3.775 90)
			(size 0.3 1.55)
			(layers "B.Cu" "B.Mask" "B.Paste")
			(net 177 "unconnected-(J501-NC-Pad69)")
			(pinfunction "NC")
			(pintype "no_connect")
		)
		(pad "70" smd rect
			(at 7.998 -3.773 90)
			(size 0.3 1.55)
			(layers "B.Cu" "B.Mask" "B.Paste")
			(net 65 "3V3_SSD")
			(pinfunction "3V3")
			(pintype "passive")
		)
		(pad "71" smd rect
			(at 8.247 3.775 90)
			(size 0.3 1.55)
			(layers "B.Cu" "B.Mask" "B.Paste")
			(net 3 "GND")
			(pinfunction "GND")
			(pintype "passive")
		)
		(pad "72" smd rect
			(at 8.497 -3.773 90)
			(size 0.3 1.55)
			(layers "B.Cu" "B.Mask" "B.Paste")
			(net 65 "3V3_SSD")
			(pinfunction "3V3")
			(pintype "passive")
		)
		(pad "73" smd rect
			(at 8.747 3.775 90)
			(size 0.3 1.55)
			(layers "B.Cu" "B.Mask" "B.Paste")
			(net 3 "GND")
			(pinfunction "GND")
			(pintype "passive")
		)
		(pad "74" smd rect
			(at 8.997 -3.773 90)
			(size 0.3 1.55)
			(layers "B.Cu" "B.Mask" "B.Paste")
			(net 65 "3V3_SSD")
			(pinfunction "3V3")
			(pintype "passive")
		)
		(pad "75" smd rect
			(at 9.247 3.775 90)
			(size 0.3 1.55)
			(layers "B.Cu" "B.Mask" "B.Paste")
			(net 3 "GND")
			(pinfunction "GND")
			(pintype "passive")
		)
		(pad "MP1" smd rect
			(at -10.352 3 90)
			(size 1.2 2.75)
			(layers "B.Cu" "B.Mask" "B.Paste")
			(net 3 "GND")
			(pinfunction "MP")
			(pintype "passive")
		)
		(pad "MP2" smd rect
			(at 10.349 3 90)
			(size 1.2 2.75)
			(layers "B.Cu" "B.Mask" "B.Paste")
			(net 3 "GND")
			(pinfunction "MP")
			(pintype "passive")
		)
	)
)
